(kicad_pcb
	(version 20260206)
	(generator "pcbnew")
	(generator_version "10.0")
	(general
		(thickness 1.6)
		(legacy_teardrops no)
	)
	(paper "A4")
	(title_block
		(title "Wiwynn_Tioga_Pass_MB.brd")
		(comment 1 "Tioga Pass / footprints 883-888 of 4770")
	)
	(layers
		(0 "F.Cu" signal "TOP")
		(4 "In1.Cu" signal "L2GND")
		(6 "In2.Cu" signal "L3")
		(8 "In3.Cu" signal "L4GND")
		(10 "In4.Cu" signal "L5")
		(12 "In5.Cu" signal "L6GND")
		(14 "In6.Cu" signal "L7VCC")
		(16 "In7.Cu" signal "L8VCC")
		(18 "In8.Cu" signal "L9GND")
		(20 "In9.Cu" signal "L10")
		(22 "In10.Cu" signal "L11GND")
		(24 "In11.Cu" signal "L12")
		(26 "In12.Cu" signal "L13GND")
		(2 "B.Cu" signal "BOTTOM")
		(9 "F.Adhes" user "F.Adhesive")
		(11 "B.Adhes" user "B.Adhesive")
		(13 "F.Paste" user "Package Geometry/Pastemask Top")
		(15 "B.Paste" user "Package Geometry/Pastemask Bottom")
		(5 "F.SilkS" user "Ref Des/Silkscreen Top")
		(7 "B.SilkS" user "Ref Des/Silkscreen Bottom")
		(1 "F.Mask" user "Board Geometry/Soldermask Top")
		(3 "B.Mask" user "Board Geometry/Soldermask Bottom")
		(17 "Dwgs.User" user "User.Drawings")
		(19 "Cmts.User" user "User.Comments")
		(21 "Eco1.User" user "User.Eco1")
		(23 "Eco2.User" user "User.Eco2")
		(25 "Edge.Cuts" user "Board Geometry/Outline")
		(27 "Margin" user)
		(31 "F.CrtYd" user "Package Geometry/Place Bound Top")
		(29 "B.CrtYd" user "Package Geometry/Place Bound Bottom")
		(35 "F.Fab" user "Ref Des/Assembly Top")
		(33 "B.Fab" user "Ref Des/Assembly Bottom")
	)
	(footprint ""
		(layer "F.Cu")
		(at -0.342138 -6.936486)
		(property "Reference" "R1G26"
			(at 0 0 0)
			(layer "F.SilkS")
			(hide yes)
			(effects
				(font
					(size 1.27 1.27)
				)
			)
		)
		(property "Value" ""
			(at 0 0 0)
			(layer "F.Fab")
			(effects
				(font
					(size 1.27 1.27)
				)
			)
		)
		(duplicate_pad_numbers_are_jumpers no)
		(fp_poly
			(pts
				(xy -0.2794 -0.1016) (xy 0.2794 -0.1016) (xy 0.2794 0.9906) (xy -0.2794 0.9906)
			)
			(stroke
				(width 0)
				(type default)
			)
			(fill no)
			(layer "F.CrtYd")
		)
		(fp_line
			(start -0.2794 -0.1016)
			(end -0.2794 0.9906)
			(stroke
				(width 0.1)
				(type default)
			)
			(layer "F.Fab")
		)
		(fp_line
			(start -0.2794 0.9906)
			(end 0.2794 0.9906)
			(stroke
				(width 0.1)
				(type default)
			)
			(layer "F.Fab")
		)
		(fp_line
			(start 0.2794 -0.1016)
			(end -0.2794 -0.1016)
			(stroke
				(width 0.1)
				(type default)
			)
			(layer "F.Fab")
		)
		(fp_line
			(start 0.2794 0.9906)
			(end 0.2794 -0.1016)
			(stroke
				(width 0.1)
				(type default)
			)
			(layer "F.Fab")
		)
		(pad "1" smd rect
			(at 0 0)
			(size 0.508 0.508)
			(layers "F.Cu" "F.Mask" "F.Paste")
			(net "VR_PVDDQ_GHJ_PH1_OCSET")
		)
		(pad "2" smd rect
			(at 0 0.889)
			(size 0.508 0.508)
			(layers "F.Cu" "F.Mask" "F.Paste")
			(net "GND")
		)
		(zone
			(layer "F.Cu")
			(hatch none 0.5)
			(connect_pads
				(clearance 0)
			)
			(min_thickness 0.25)
			(keepout
				(tracks allowed)
				(vias not_allowed)
				(pads allowed)
				(copperpour not_allowed)
				(footprints allowed)
			)
			(placement
				(enabled no)
				(sheetname "")
			)
			(fill
				(thermal_gap 0.5)
				(thermal_bridge_width 0.5)
				(island_removal_mode 0)
			)
			(polygon
				(pts
					(xy -0.596138 -6.682486) (xy -0.088138 -6.682486) (xy -0.088138 -6.301486) (xy -0.596138 -6.301486)
				)
			)
		)
		(zone
			(layer "F.Cu")
			(hatch none 0.5)
			(connect_pads
				(clearance 0)
			)
			(min_thickness 0.25)
			(keepout
				(tracks not_allowed)
				(vias allowed)
				(pads allowed)
				(copperpour not_allowed)
				(footprints allowed)
			)
			(placement
				(enabled no)
				(sheetname "")
			)
			(fill
				(thermal_gap 0.5)
				(thermal_bridge_width 0.5)
				(island_removal_mode 0)
			)
			(polygon
				(pts
					(xy -0.596138 -6.301486) (xy -0.088138 -6.301486) (xy -0.088138 -6.682486) (xy -0.596138 -6.682486)
				)
			)
		)
	)
	(footprint ""
		(layer "F.Cu")
		(at 489.3945 -144.638268 90)
		(property "Reference" "R1L24"
			(at 0 0 90)
			(layer "F.SilkS")
			(hide yes)
			(effects
				(font
					(size 1.27 1.27)
				)
			)
		)
		(property "Value" ""
			(at 0 0 90)
			(layer "F.Fab")
			(effects
				(font
					(size 1.27 1.27)
				)
			)
		)
		(duplicate_pad_numbers_are_jumpers no)
		(fp_poly
			(pts
				(xy -0.2794 -0.1016) (xy 0.2794 -0.1016) (xy 0.2794 0.9906) (xy -0.2794 0.9906)
			)
			(stroke
				(width 0)
				(type default)
			)
			(fill no)
			(layer "F.CrtYd")
		)
		(fp_line
			(start 0.2794 -0.1016)
			(end -0.2794 -0.1016)
			(stroke
				(width 0.1)
				(type default)
			)
			(layer "F.Fab")
		)
		(fp_line
			(start -0.2794 -0.1016)
			(end -0.2794 0.9906)
			(stroke
				(width 0.1)
				(type default)
			)
			(layer "F.Fab")
		)
		(fp_line
			(start 0.2794 0.9906)
			(end 0.2794 -0.1016)
			(stroke
				(width 0.1)
				(type default)
			)
			(layer "F.Fab")
		)
		(fp_line
			(start -0.2794 0.9906)
			(end 0.2794 0.9906)
			(stroke
				(width 0.1)
				(type default)
			)
			(layer "F.Fab")
		)
		(pad "1" smd rect
			(at 0 0 90)
			(size 0.508 0.508)
			(layers "F.Cu" "F.Mask" "F.Paste")
			(net "LED_POSTCODE_3")
		)
		(pad "2" smd rect
			(at 0 0.889 90)
			(size 0.508 0.508)
			(layers "F.Cu" "F.Mask" "F.Paste")
			(net "LED_POSTCODE_3_R")
		)
		(zone
			(layer "F.Cu")
			(hatch none 0.5)
			(connect_pads
				(clearance 0)
			)
			(min_thickness 0.25)
			(keepout
				(tracks allowed)
				(vias not_allowed)
				(pads allowed)
				(copperpour not_allowed)
				(footprints allowed)
			)
			(placement
				(enabled no)
				(sheetname "")
			)
			(fill
				(thermal_gap 0.5)
				(thermal_bridge_width 0.5)
				(island_removal_mode 0)
			)
			(polygon
				(pts
					(xy 489.6485 -144.384268) (xy 489.6485 -144.892268) (xy 490.0295 -144.892268) (xy 490.0295 -144.384268)
				)
			)
		)
		(zone
			(layer "F.Cu")
			(hatch none 0.5)
			(connect_pads
				(clearance 0)
			)
			(min_thickness 0.25)
			(keepout
				(tracks not_allowed)
				(vias allowed)
				(pads allowed)
				(copperpour not_allowed)
				(footprints allowed)
			)
			(placement
				(enabled no)
				(sheetname "")
			)
			(fill
				(thermal_gap 0.5)
				(thermal_bridge_width 0.5)
				(island_removal_mode 0)
			)
			(polygon
				(pts
					(xy 490.0295 -144.384268) (xy 490.0295 -144.892268) (xy 489.6485 -144.892268) (xy 489.6485 -144.384268)
				)
			)
		)
	)
	(footprint ""
		(layer "F.Cu")
		(at 496.581684 -19.373088 90)
		(property "Reference" "C7E8"
			(at 0 0 90)
			(layer "F.SilkS")
			(hide yes)
			(effects
				(font
					(size 1.27 1.27)
				)
			)
		)
		(property "Value" ""
			(at 0 0 90)
			(layer "F.Fab")
			(effects
				(font
					(size 1.27 1.27)
				)
			)
		)
		(duplicate_pad_numbers_are_jumpers no)
		(fp_rect
			(start -0.7239 1.9939)
			(end 0.7239 -0.2159)
			(stroke
				(width 0)
				(type default)
			)
			(fill no)
			(layer "F.CrtYd")
		)
		(fp_line
			(start 0.7239 -0.2159)
			(end -0.7239 -0.2159)
			(stroke
				(width 0.1)
				(type default)
			)
			(layer "F.Fab")
		)
		(fp_line
			(start -0.7239 -0.2159)
			(end -0.7239 1.9939)
			(stroke
				(width 0.1)
				(type default)
			)
			(layer "F.Fab")
		)
		(fp_line
			(start 0.7239 1.9939)
			(end 0.7239 -0.2159)
			(stroke
				(width 0.1)
				(type default)
			)
			(layer "F.Fab")
		)
		(fp_line
			(start -0.7239 1.9939)
			(end 0.7239 1.9939)
			(stroke
				(width 0.1)
				(type default)
			)
			(layer "F.Fab")
		)
		(pad "1" smd rect
			(at 0 0 90)
			(size 1.27 1.016)
			(layers "F.Cu" "F.Mask" "F.Paste")
			(net "P12V")
		)
		(pad "2" smd rect
			(at 0 1.778 90)
			(size 1.27 1.016)
			(layers "F.Cu" "F.Mask" "F.Paste")
			(net "GND")
		)
		(zone
			(layer "F.Cu")
			(hatch none 0.5)
			(connect_pads
				(clearance 0)
			)
			(min_thickness 0.25)
			(keepout
				(tracks not_allowed)
				(vias allowed)
				(pads allowed)
				(copperpour not_allowed)
				(footprints allowed)
			)
			(placement
				(enabled no)
				(sheetname "")
			)
			(fill
				(thermal_gap 0.5)
				(thermal_bridge_width 0.5)
				(island_removal_mode 0)
			)
			(polygon
				(pts
					(xy 497.851684 -18.738088) (xy 497.851684 -20.008088) (xy 497.089684 -20.008088) (xy 497.089684 -18.738088)
				)
			)
		)
	)
	(footprint ""
		(layer "F.Cu")
		(at 16.383 -97.8916 -90)
		(property "Reference" "C1C9"
			(at 0 0 270)
			(layer "F.SilkS")
			(hide yes)
			(effects
				(font
					(size 1.27 1.27)
				)
			)
		)
		(property "Value" ""
			(at 0 0 270)
			(layer "F.Fab")
			(effects
				(font
					(size 1.27 1.27)
				)
			)
		)
		(duplicate_pad_numbers_are_jumpers no)
		(fp_rect
			(start 0.3048 0.9906)
			(end -0.3048 -0.1016)
			(stroke
				(width 0)
				(type default)
			)
			(fill no)
			(layer "F.CrtYd")
		)
		(fp_line
			(start -0.3048 0.9906)
			(end 0.3048 0.9906)
			(stroke
				(width 0.1)
				(type default)
			)
			(layer "F.Fab")
		)
		(fp_line
			(start 0.3048 0.9906)
			(end 0.3048 -0.1016)
			(stroke
				(width 0.1)
				(type default)
			)
			(layer "F.Fab")
		)
		(fp_line
			(start -0.3048 -0.1016)
			(end -0.3048 0.9906)
			(stroke
				(width 0.1)
				(type default)
			)
			(layer "F.Fab")
		)
		(fp_line
			(start 0.3048 -0.1016)
			(end -0.3048 -0.1016)
			(stroke
				(width 0.1)
				(type default)
			)
			(layer "F.Fab")
		)
		(pad "1" smd rect
			(at 0 0 270)
			(size 0.508 0.508)
			(layers "F.Cu" "F.Mask" "F.Paste")
			(net "VR_PVCCIN_CPU1_VDD")
		)
		(pad "2" smd rect
			(at 0 0.889 270)
			(size 0.508 0.508)
			(layers "F.Cu" "F.Mask" "F.Paste")
			(net "GND")
		)
		(zone
			(layer "F.Cu")
			(hatch none 0.5)
			(connect_pads
				(clearance 0)
			)
			(min_thickness 0.25)
			(keepout
				(tracks not_allowed)
				(vias allowed)
				(pads allowed)
				(copperpour not_allowed)
				(footprints allowed)
			)
			(placement
				(enabled no)
				(sheetname "")
			)
			(fill
				(thermal_gap 0.5)
				(thermal_bridge_width 0.5)
				(island_removal_mode 0)
			)
			(polygon
				(pts
					(xy 15.748 -97.6376) (xy 16.129 -97.6376) (xy 16.129 -98.1456) (xy 15.748 -98.1456)
				)
			)
		)
		(zone
			(layer "F.Cu")
			(hatch none 0.5)
			(connect_pads
				(clearance 0)
			)
			(min_thickness 0.25)
			(keepout
				(tracks allowed)
				(vias not_allowed)
				(pads allowed)
				(copperpour not_allowed)
				(footprints allowed)
			)
			(placement
				(enabled no)
				(sheetname "")
			)
			(fill
				(thermal_gap 0.5)
				(thermal_bridge_width 0.5)
				(island_removal_mode 0)
			)
			(polygon
				(pts
					(xy 15.748 -97.6376) (xy 16.129 -97.6376) (xy 16.129 -98.1456) (xy 15.748 -98.1456)
				)
			)
		)
	)
	(footprint ""
		(layer "F.Cu")
		(at 499.872 -155.321)
		(property "Reference" "DS9A1"
			(at -0.49276 -1.47447 0)
			(unlocked yes)
			(layer "F.SilkS")
			(effects
				(font
					(size 0.7874 0.5842)
					(thickness 0.1524)
				)
			)
		)
		(property "Value" ""
			(at 0 0 0)
			(layer "F.Fab")
			(effects
				(font
					(size 1.27 1.27)
				)
			)
		)
		(duplicate_pad_numbers_are_jumpers no)
		(fp_line
			(start -1.728978 -0.9525)
			(end -1.248156 -1.785366)
			(stroke
				(width 0.1524)
				(type default)
			)
			(layer "F.SilkS")
		)
		(fp_line
			(start -1.248156 -2.908808)
			(end -1.248156 -1.785366)
			(stroke
				(width 0.1524)
				(type default)
			)
			(layer "F.SilkS")
		)
		(fp_line
			(start -1.248156 -1.785366)
			(end -0.767334 -0.9525)
			(stroke
				(width 0.1524)
				(type default)
			)
			(layer "F.SilkS")
		)
		(fp_line
			(start -1.248156 -0.9525)
			(end -1.728978 -0.9525)
			(stroke
				(width 0.1524)
				(type default)
			)
			(layer "F.SilkS")
		)
		(fp_line
			(start -1.248156 -0.040894)
			(end -1.248156 -0.9525)
			(stroke
				(width 0.1524)
				(type default)
			)
			(layer "F.SilkS")
		)
		(fp_line
			(start -0.767334 -1.785366)
			(end -1.728978 -1.785366)
			(stroke
				(width 0.1524)
				(type default)
			)
			(layer "F.SilkS")
		)
		(fp_line
			(start -0.767334 -0.9525)
			(end -1.248156 -0.9525)
			(stroke
				(width 0.1524)
				(type default)
			)
			(layer "F.SilkS")
		)
		(fp_poly
			(pts
				(xy -0.5715 2.2098) (xy -0.5715 0.2032) (xy 0.5715 0.2032) (xy 0.5715 0.6985)
				(arc
					(start 0.726948 0.6985)
					(mid 1.29058 0.932279)
					(end 1.524 1.49606)
				)
				(arc
					(start 1.524 2.05994)
					(mid 1.2904 2.6239)
					(end 0.72644 2.8575)
				)
				(xy 0.5715 2.8575) (xy 0.5715 3.3528) (xy -0.5715 3.3528)
			)
			(stroke
				(width 0)
				(type default)
			)
			(fill no)
			(layer "F.CrtYd")
		)
		(fp_line
			(start -1.720088 -0.958342)
			(end -1.239266 -1.791208)
			(stroke
				(width 0.1)
				(type default)
			)
			(layer "F.Fab")
		)
		(fp_line
			(start -1.239266 -1.791208)
			(end -1.239266 -2.91465)
			(stroke
				(width 0.1)
				(type default)
			)
			(layer "F.Fab")
		)
		(fp_line
			(start -1.239266 -1.791208)
			(end -0.758444 -0.958342)
			(stroke
				(width 0.1)
				(type default)
			)
			(layer "F.Fab")
		)
		(fp_line
			(start -1.239266 -0.958342)
			(end -1.239266 -0.046736)
			(stroke
				(width 0.1)
				(type default)
			)
			(layer "F.Fab")
		)
		(fp_line
			(start -0.758444 -1.791208)
			(end -1.720088 -1.791208)
			(stroke
				(width 0.1)
				(type default)
			)
			(layer "F.Fab")
		)
		(fp_line
			(start -0.758444 -0.958342)
			(end -1.720088 -0.958342)
			(stroke
				(width 0.1)
				(type default)
			)
			(layer "F.Fab")
		)
		(fp_line
			(start -0.5715 0.2032)
			(end 0.5715 0.2032)
			(stroke
				(width 0.1)
				(type default)
			)
			(layer "F.Fab")
		)
		(fp_line
			(start -0.5715 0.7112)
			(end 0.5715 0.7112)
			(stroke
				(width 0.1)
				(type default)
			)
			(layer "F.Fab")
		)
		(fp_line
			(start -0.5715 2.8448)
			(end 0.5715 2.8448)
			(stroke
				(width 0.1)
				(type default)
			)
			(layer "F.Fab")
		)
		(fp_line
			(start -0.5715 3.3528)
			(end -0.5715 0.2032)
			(stroke
				(width 0.1)
				(type default)
			)
			(layer "F.Fab")
		)
		(fp_line
			(start 0.5715 0.2032)
			(end 0.5715 3.3528)
			(stroke
				(width 0.1)
				(type default)
			)
			(layer "F.Fab")
		)
		(fp_line
			(start 0.5715 2.8575)
			(end 0.72644 2.8575)
			(stroke
				(width 0.1)
				(type default)
			)
			(layer "F.Fab")
		)
		(fp_line
			(start 0.5715 3.3528)
			(end -0.5715 3.3528)
			(stroke
				(width 0.1)
				(type default)
			)
			(layer "F.Fab")
		)
		(fp_line
			(start 0.72644 0.6985)
			(end 0.5715 0.6985)
			(stroke
				(width 0.1)
				(type default)
			)
			(layer "F.Fab")
		)
		(fp_line
			(start 1.524 2.05994)
			(end 1.524 1.49606)
			(stroke
				(width 0.1)
				(type default)
			)
			(layer "F.Fab")
		)
		(fp_arc
			(start 0.72644 0.6985)
			(mid 1.290388 0.932112)
			(end 1.524 1.49606)
			(stroke
				(width 0.1)
				(type default)
			)
			(layer "F.Fab")
		)
		(fp_arc
			(start 1.524 2.05994)
			(mid 1.290388 2.623888)
			(end 0.72644 2.8575)
			(stroke
				(width 0.1)
				(type default)
			)
			(layer "F.Fab")
		)
		(pad "1" smd rect
			(at 0 0)
			(size 1.524 1.524)
			(layers "F.Cu" "F.Mask" "F.Paste")
			(net "FP_ID_LED_P5V_STBY_N")
		)
		(pad "2" smd rect
			(at 0 3.556)
			(size 1.524 1.524)
			(layers "F.Cu" "F.Mask" "F.Paste")
			(net "FP_ID_LED_XOR_R")
		)
		(pad "3" smd rect
			(at -0.762 1.778)
			(size 0.889 0.889)
			(layers "F.Cu" "F.Mask" "F.Paste")
			(net "Net_6474")
		)
		(zone
			(layer "F.Cu")
			(hatch none 0.5)
			(connect_pads
				(clearance 0)
			)
			(min_thickness 0.25)
			(keepout
				(tracks allowed)
				(vias not_allowed)
				(pads allowed)
				(copperpour not_allowed)
				(footprints allowed)
			)
			(placement
				(enabled no)
				(sheetname "")
			)
			(fill
				(thermal_gap 0.5)
				(thermal_bridge_width 0.5)
				(island_removal_mode 0)
			)
			(polygon
				(pts
					(xy 500.4435 -154.5082) (xy 500.4435 -152.5778) (xy 499.3005 -152.5778) (xy 499.3005 -154.5082)
				)
			)
		)
	)
	(footprint ""
		(layer "F.Cu")
		(at 359.876598 -10.916158)
		(property "Reference" "R8W14"
			(at -0.8382 -0.67818 0)
			(unlocked yes)
			(layer "F.SilkS")
			(effects
				(font
					(size 0.4064 0.254)
					(thickness 0.1524)
				)
				(justify left)
			)
		)
		(property "Value" ""
			(at 0 0 0)
			(layer "F.Fab")
			(effects
				(font
					(size 1.27 1.27)
				)
			)
		)
		(duplicate_pad_numbers_are_jumpers no)
		(fp_poly
			(pts
				(xy -0.2794 -0.1016) (xy 0.2794 -0.1016) (xy 0.2794 0.9906) (xy -0.2794 0.9906)
			)
			(stroke
				(width 0)
				(type default)
			)
			(fill no)
			(layer "F.CrtYd")
		)
		(fp_line
			(start -0.2794 -0.1016)
			(end -0.2794 0.9906)
			(stroke
				(width 0.1)
				(type default)
			)
			(layer "F.Fab")
		)
		(fp_line
			(start -0.2794 0.9906)
			(end 0.2794 0.9906)
			(stroke
				(width 0.1)
				(type default)
			)
			(layer "F.Fab")
		)
		(fp_line
			(start 0.2794 -0.1016)
			(end -0.2794 -0.1016)
			(stroke
				(width 0.1)
				(type default)
			)
			(layer "F.Fab")
		)
		(fp_line
			(start 0.2794 0.9906)
			(end 0.2794 -0.1016)
			(stroke
				(width 0.1)
				(type default)
			)
			(layer "F.Fab")
		)
		(pad "1" smd rect
			(at 0 0)
			(size 0.508 0.508)
			(layers "F.Cu" "F.Mask" "F.Paste")
			(net "JTAG_RISER_TDO_R")
		)
		(pad "2" smd rect
			(at 0 0.889)
			(size 0.508 0.508)
			(layers "F.Cu" "F.Mask" "F.Paste")
			(net "JTAG_RISER_TDO")
		)
		(zone
			(layer "F.Cu")
			(hatch none 0.5)
			(connect_pads
				(clearance 0)
			)
			(min_thickness 0.25)
			(keepout
				(tracks allowed)
				(vias not_allowed)
				(pads allowed)
				(copperpour not_allowed)
				(footprints allowed)
			)
			(placement
				(enabled no)
				(sheetname "")
			)
			(fill
				(thermal_gap 0.5)
				(thermal_bridge_width 0.5)
				(island_removal_mode 0)
			)
			(polygon
				(pts
					(xy 359.622598 -10.662158) (xy 360.130598 -10.662158) (xy 360.130598 -10.281158) (xy 359.622598 -10.281158)
				)
			)
		)
		(zone
			(layer "F.Cu")
			(hatch none 0.5)
			(connect_pads
				(clearance 0)
			)
			(min_thickness 0.25)
			(keepout
				(tracks not_allowed)
				(vias allowed)
				(pads allowed)
				(copperpour not_allowed)
				(footprints allowed)
			)
			(placement
				(enabled no)
				(sheetname "")
			)
			(fill
				(thermal_gap 0.5)
				(thermal_bridge_width 0.5)
				(island_removal_mode 0)
			)
			(polygon
				(pts
					(xy 359.622598 -10.281158) (xy 360.130598 -10.281158) (xy 360.130598 -10.662158) (xy 359.622598 -10.662158)
				)
			)
		)
	)
)
